(kicad_pcb
	(version 20241229)
	(generator "pcbnew")
	(generator_version "9.0")
	(general
		(thickness 1.599998)
		(legacy_teardrops no)
	)
	(paper "A4")
	(title_block
		(title "Artix - Datacenter Secure Control Module (DC-SCM)")
		(date "2024-11-06")
		(rev "1.1.3")
		(comment 9 "footprints 350-354 of 544")
	)
	(layers
		(0 "F.Cu" signal)
		(4 "In1.Cu" signal)
		(6 "In2.Cu" signal)
		(8 "In3.Cu" signal)
		(10 "In4.Cu" signal)
		(12 "In5.Cu" signal)
		(14 "In6.Cu" signal)
		(2 "B.Cu" signal)
		(9 "F.Adhes" user "F.Adhesive")
		(11 "B.Adhes" user "B.Adhesive")
		(13 "F.Paste" user)
		(15 "B.Paste" user)
		(5 "F.SilkS" user "F.Silkscreen")
		(7 "B.SilkS" user "B.Silkscreen")
		(1 "F.Mask" user)
		(3 "B.Mask" user)
		(17 "Dwgs.User" user "User.Drawings")
		(19 "Cmts.User" user "User.Comments")
		(21 "Eco1.User" user "User.Eco1")
		(23 "Eco2.User" user "User.Eco2")
		(25 "Edge.Cuts" user)
		(27 "Margin" user)
		(31 "F.CrtYd" user "F.Courtyard")
		(29 "B.CrtYd" user "B.Courtyard")
		(35 "F.Fab" user)
		(33 "B.Fab" user)
	)
	(footprint "antmicro-footprints:C_0402_1005Metric"
		(layer "B.Cu")
		(at 100.845 90.765 -90)
		(descr "Capacitor SMD 0402")
		(tags "capacitor SMD 0402")
		(property "Reference" "C204"
			(at -3.649 -0.4 90)
			(layer "B.SilkS")
			(effects
				(font
					(size 0.7 0.7)
					(thickness 0.15)
				)
				(justify left bottom mirror)
			)
		)
		(property "Value" "C_470n_0402"
			(at 0 -1.4 90)
			(layer "B.Fab")
			(effects
				(font
					(size 0.7 0.7)
					(thickness 0.15)
				)
				(justify left bottom mirror)
			)
		)
		(property "Datasheet" "https://product.tdk.com/en/search/capacitor/ceramic/mlcc/info?part_no=C1005X5R1E474M050BB"
			(at 0 0 270)
			(layer "F.Fab")
			(hide yes)
			(effects
				(font
					(size 1.27 1.27)
					(thickness 0.15)
				)
			)
		)
		(property "Description" "SMD Multilayer Ceramic Capacitor, 0.47 µF, 25 V, 0402 [1005 Metric], ± 20%, X5R, C"
			(at 0 0 270)
			(layer "F.Fab")
			(hide yes)
			(effects
				(font
					(size 1.27 1.27)
					(thickness 0.15)
				)
			)
		)
		(property "Author" "Antmicro"
			(at 10.08 191.61 0)
			(layer "B.Fab")
			(hide yes)
			(effects
				(font
					(size 1 1)
					(thickness 0.15)
				)
				(justify mirror)
			)
		)
		(property "Dielectric" ""
			(at 10.08 191.61 0)
			(layer "B.Fab")
			(hide yes)
			(effects
				(font
					(size 1 1)
					(thickness 0.15)
				)
				(justify mirror)
			)
		)
		(property "License" "Apache-2.0"
			(at 10.08 191.61 0)
			(layer "B.Fab")
			(hide yes)
			(effects
				(font
					(size 1 1)
					(thickness 0.15)
				)
				(justify mirror)
			)
		)
		(property "MPN" "C1005X5R1E474M050BB"
			(at 10.08 191.61 0)
			(layer "B.Fab")
			(hide yes)
			(effects
				(font
					(size 1 1)
					(thickness 0.15)
				)
				(justify mirror)
			)
		)
		(property "Manufacturer" "TDK"
			(at 10.08 191.61 0)
			(layer "B.Fab")
			(hide yes)
			(effects
				(font
					(size 1 1)
					(thickness 0.15)
				)
				(justify mirror)
			)
		)
		(property "Val" "470n"
			(at 10.08 191.61 0)
			(layer "B.Fab")
			(hide yes)
			(effects
				(font
					(size 1 1)
					(thickness 0.15)
				)
				(justify mirror)
			)
		)
		(property "Voltage" ""
			(at 10.08 191.61 0)
			(layer "B.Fab")
			(hide yes)
			(effects
				(font
					(size 1 1)
					(thickness 0.15)
				)
				(justify mirror)
			)
		)
		(sheetname "/Ethernet/")
		(sheetfile "ethernet.kicad_sch")
		(attr smd)
		(fp_rect
			(start -0.925 0.47)
			(end 0.925 -0.47)
			(stroke
				(width 0.05)
				(type default)
			)
			(fill no)
			(layer "B.CrtYd")
		)
		(fp_line
			(start -0.494 0.25)
			(end 0.504 0.25)
			(stroke
				(width 0.15)
				(type solid)
			)
			(layer "B.Fab")
		)
		(fp_line
			(start 0.504 0.25)
			(end 0.504 -0.248)
			(stroke
				(width 0.15)
				(type solid)
			)
			(layer "B.Fab")
		)
		(fp_line
			(start -0.494 -0.248)
			(end -0.494 0.25)
			(stroke
				(width 0.15)
				(type solid)
			)
			(layer "B.Fab")
		)
		(fp_line
			(start 0.504 -0.248)
			(end -0.494 -0.248)
			(stroke
				(width 0.15)
				(type solid)
			)
			(layer "B.Fab")
		)
		(pad "1" smd roundrect
			(at -0.48 0 270)
			(size 0.59 0.64)
			(layers "B.Cu" "B.Mask" "B.Paste")
			(roundrect_rratio 0.25)
			(net 1 "GND")
			(pintype "passive")
		)
		(pad "2" smd roundrect
			(at 0.48 0 270)
			(size 0.59 0.64)
			(layers "B.Cu" "B.Mask" "B.Paste")
			(roundrect_rratio 0.25)
			(net 405 "/Ethernet/AVDDL")
			(pintype "passive")
		)
	)
	(footprint "antmicro-footprints:C_0402_1005Metric"
		(layer "B.Cu")
		(at 101.14 98.12 -90)
		(descr "Capacitor SMD 0402")
		(tags "capacitor SMD 0402")
		(property "Reference" "C205"
			(at -3.62 -0.36 90)
			(layer "B.SilkS")
			(effects
				(font
					(size 0.7 0.7)
					(thickness 0.15)
				)
				(justify left bottom mirror)
			)
		)
		(property "Value" "C_470n_0402"
			(at 0 -1.4 90)
			(layer "B.Fab")
			(effects
				(font
					(size 0.7 0.7)
					(thickness 0.15)
				)
				(justify left bottom mirror)
			)
		)
		(property "Datasheet" "https://product.tdk.com/en/search/capacitor/ceramic/mlcc/info?part_no=C1005X5R1E474M050BB"
			(at 0 0 270)
			(layer "F.Fab")
			(hide yes)
			(effects
				(font
					(size 1.27 1.27)
					(thickness 0.15)
				)
			)
		)
		(property "Description" "SMD Multilayer Ceramic Capacitor, 0.47 µF, 25 V, 0402 [1005 Metric], ± 20%, X5R, C"
			(at 0 0 270)
			(layer "F.Fab")
			(hide yes)
			(effects
				(font
					(size 1.27 1.27)
					(thickness 0.15)
				)
			)
		)
		(property "Author" "Antmicro"
			(at 3.02 199.26 0)
			(layer "B.Fab")
			(hide yes)
			(effects
				(font
					(size 1 1)
					(thickness 0.15)
				)
				(justify mirror)
			)
		)
		(property "Dielectric" ""
			(at 3.02 199.26 0)
			(layer "B.Fab")
			(hide yes)
			(effects
				(font
					(size 1 1)
					(thickness 0.15)
				)
				(justify mirror)
			)
		)
		(property "License" "Apache-2.0"
			(at 3.02 199.26 0)
			(layer "B.Fab")
			(hide yes)
			(effects
				(font
					(size 1 1)
					(thickness 0.15)
				)
				(justify mirror)
			)
		)
		(property "MPN" "C1005X5R1E474M050BB"
			(at 3.02 199.26 0)
			(layer "B.Fab")
			(hide yes)
			(effects
				(font
					(size 1 1)
					(thickness 0.15)
				)
				(justify mirror)
			)
		)
		(property "Manufacturer" "TDK"
			(at 3.02 199.26 0)
			(layer "B.Fab")
			(hide yes)
			(effects
				(font
					(size 1 1)
					(thickness 0.15)
				)
				(justify mirror)
			)
		)
		(property "Val" "470n"
			(at 3.02 199.26 0)
			(layer "B.Fab")
			(hide yes)
			(effects
				(font
					(size 1 1)
					(thickness 0.15)
				)
				(justify mirror)
			)
		)
		(property "Voltage" ""
			(at 3.02 199.26 0)
			(layer "B.Fab")
			(hide yes)
			(effects
				(font
					(size 1 1)
					(thickness 0.15)
				)
				(justify mirror)
			)
		)
		(sheetname "/Ethernet/")
		(sheetfile "ethernet.kicad_sch")
		(attr smd)
		(fp_rect
			(start -0.925 0.47)
			(end 0.925 -0.47)
			(stroke
				(width 0.05)
				(type default)
			)
			(fill no)
			(layer "B.CrtYd")
		)
		(fp_line
			(start -0.494 0.25)
			(end 0.504 0.25)
			(stroke
				(width 0.15)
				(type solid)
			)
			(layer "B.Fab")
		)
		(fp_line
			(start 0.504 0.25)
			(end 0.504 -0.248)
			(stroke
				(width 0.15)
				(type solid)
			)
			(layer "B.Fab")
		)
		(fp_line
			(start -0.494 -0.248)
			(end -0.494 0.25)
			(stroke
				(width 0.15)
				(type solid)
			)
			(layer "B.Fab")
		)
		(fp_line
			(start 0.504 -0.248)
			(end -0.494 -0.248)
			(stroke
				(width 0.15)
				(type solid)
			)
			(layer "B.Fab")
		)
		(pad "1" smd roundrect
			(at -0.48 0 270)
			(size 0.59 0.64)
			(layers "B.Cu" "B.Mask" "B.Paste")
			(roundrect_rratio 0.25)
			(net 1 "GND")
			(pintype "passive")
		)
		(pad "2" smd roundrect
			(at 0.48 0 270)
			(size 0.59 0.64)
			(layers "B.Cu" "B.Mask" "B.Paste")
			(roundrect_rratio 0.25)
			(net 339 "VCC1V2")
			(pintype "passive")
		)
	)
	(footprint "antmicro-footprints:C_0402_1005Metric"
		(layer "B.Cu")
		(at 98.419 90.78 -90)
		(descr "Capacitor SMD 0402")
		(tags "capacitor SMD 0402")
		(property "Reference" "C206"
			(at -3.68 1.519 90)
			(layer "B.SilkS")
			(effects
				(font
					(size 0.7 0.7)
					(thickness 0.15)
				)
				(justify left bottom mirror)
			)
		)
		(property "Value" "C_4u7_0402"
			(at 0 -1.4 90)
			(layer "B.Fab")
			(effects
				(font
					(size 0.7 0.7)
					(thickness 0.15)
				)
				(justify left bottom mirror)
			)
		)
		(property "Datasheet" "https://www.murata.com/products/productdetail?partno=GRM155R61A475MEAA%23"
			(at 0 0 270)
			(layer "F.Fab")
			(hide yes)
			(effects
				(font
					(size 1.27 1.27)
					(thickness 0.15)
				)
			)
		)
		(property "Description" "SMD Multilayer Ceramic Capacitor, 4.7 µF, 10 V, 0402 [1005 Metric], ± 20%, X5R, GRM Series"
			(at 0 0 270)
			(layer "F.Fab")
			(hide yes)
			(effects
				(font
					(size 1.27 1.27)
					(thickness 0.15)
				)
			)
		)
		(property "Author" "Antmicro"
			(at 7.639 189.199 0)
			(layer "B.Fab")
			(hide yes)
			(effects
				(font
					(size 1 1)
					(thickness 0.15)
				)
				(justify mirror)
			)
		)
		(property "Dielectric" ""
			(at 7.639 189.199 0)
			(layer "B.Fab")
			(hide yes)
			(effects
				(font
					(size 1 1)
					(thickness 0.15)
				)
				(justify mirror)
			)
		)
		(property "License" "Apache-2.0"
			(at 7.639 189.199 0)
			(layer "B.Fab")
			(hide yes)
			(effects
				(font
					(size 1 1)
					(thickness 0.15)
				)
				(justify mirror)
			)
		)
		(property "MPN" "GRM155R61A475MEAAD"
			(at 7.639 189.199 0)
			(layer "B.Fab")
			(hide yes)
			(effects
				(font
					(size 1 1)
					(thickness 0.15)
				)
				(justify mirror)
			)
		)
		(property "Manufacturer" "Murata"
			(at 7.639 189.199 0)
			(layer "B.Fab")
			(hide yes)
			(effects
				(font
					(size 1 1)
					(thickness 0.15)
				)
				(justify mirror)
			)
		)
		(property "Val" "4u7"
			(at 7.639 189.199 0)
			(layer "B.Fab")
			(hide yes)
			(effects
				(font
					(size 1 1)
					(thickness 0.15)
				)
				(justify mirror)
			)
		)
		(property "Voltage" ""
			(at 7.639 189.199 0)
			(layer "B.Fab")
			(hide yes)
			(effects
				(font
					(size 1 1)
					(thickness 0.15)
				)
				(justify mirror)
			)
		)
		(sheetname "/Ethernet/")
		(sheetfile "ethernet.kicad_sch")
		(attr smd)
		(fp_rect
			(start -0.925 0.47)
			(end 0.925 -0.47)
			(stroke
				(width 0.05)
				(type default)
			)
			(fill no)
			(layer "B.CrtYd")
		)
		(fp_line
			(start -0.494 0.25)
			(end 0.504 0.25)
			(stroke
				(width 0.15)
				(type solid)
			)
			(layer "B.Fab")
		)
		(fp_line
			(start 0.504 0.25)
			(end 0.504 -0.248)
			(stroke
				(width 0.15)
				(type solid)
			)
			(layer "B.Fab")
		)
		(fp_line
			(start -0.494 -0.248)
			(end -0.494 0.25)
			(stroke
				(width 0.15)
				(type solid)
			)
			(layer "B.Fab")
		)
		(fp_line
			(start 0.504 -0.248)
			(end -0.494 -0.248)
			(stroke
				(width 0.15)
				(type solid)
			)
			(layer "B.Fab")
		)
		(pad "1" smd roundrect
			(at -0.48 0 270)
			(size 0.59 0.64)
			(layers "B.Cu" "B.Mask" "B.Paste")
			(roundrect_rratio 0.25)
			(net 1 "GND")
			(pintype "passive")
		)
		(pad "2" smd roundrect
			(at 0.48 0 270)
			(size 0.59 0.64)
			(layers "B.Cu" "B.Mask" "B.Paste")
			(roundrect_rratio 0.25)
			(net 406 "/Ethernet/AVDDH")
			(pintype "passive")
		)
	)
	(footprint "antmicro-footprints:C_0402_1005Metric"
		(layer "B.Cu")
		(at 103.7 90.765 -90)
		(descr "Capacitor SMD 0402")
		(tags "capacitor SMD 0402")
		(property "Reference" "C209"
			(at -3.649 -0.4 90)
			(layer "B.SilkS")
			(effects
				(font
					(size 0.7 0.7)
					(thickness 0.15)
				)
				(justify left bottom mirror)
			)
		)
		(property "Value" "C_10n_0402"
			(at 0 -1.4 90)
			(layer "B.Fab")
			(effects
				(font
					(size 0.7 0.7)
					(thickness 0.15)
				)
				(justify left bottom mirror)
			)
		)
		(property "Datasheet" "https://www.murata.com/products/productdetail?partno=GRM155R71H103KA88%23"
			(at 0 0 270)
			(layer "F.Fab")
			(hide yes)
			(effects
				(font
					(size 1.27 1.27)
					(thickness 0.15)
				)
			)
		)
		(property "Description" "SMD Multilayer Ceramic Capacitor, 10000 pF, 50 V, 0402 [1005 Metric], ± 10%, X7R, GRM Series"
			(at 0 0 270)
			(layer "F.Fab")
			(hide yes)
			(effects
				(font
					(size 1.27 1.27)
					(thickness 0.15)
				)
			)
		)
		(property "Author" "Antmicro"
			(at 12.935 194.465 0)
			(layer "B.Fab")
			(hide yes)
			(effects
				(font
					(size 1 1)
					(thickness 0.15)
				)
				(justify mirror)
			)
		)
		(property "Dielectric" "X7R"
			(at 12.935 194.465 0)
			(layer "B.Fab")
			(hide yes)
			(effects
				(font
					(size 1 1)
					(thickness 0.15)
				)
				(justify mirror)
			)
		)
		(property "License" "Apache-2.0"
			(at 12.935 194.465 0)
			(layer "B.Fab")
			(hide yes)
			(effects
				(font
					(size 1 1)
					(thickness 0.15)
				)
				(justify mirror)
			)
		)
		(property "MPN" "GRM155R71H103KA88D"
			(at 12.935 194.465 0)
			(layer "B.Fab")
			(hide yes)
			(effects
				(font
					(size 1 1)
					(thickness 0.15)
				)
				(justify mirror)
			)
		)
		(property "Manufacturer" "Murata"
			(at 12.935 194.465 0)
			(layer "B.Fab")
			(hide yes)
			(effects
				(font
					(size 1 1)
					(thickness 0.15)
				)
				(justify mirror)
			)
		)
		(property "Val" "10n"
			(at 12.935 194.465 0)
			(layer "B.Fab")
			(hide yes)
			(effects
				(font
					(size 1 1)
					(thickness 0.15)
				)
				(justify mirror)
			)
		)
		(property "Voltage" "50V"
			(at 12.935 194.465 0)
			(layer "B.Fab")
			(hide yes)
			(effects
				(font
					(size 1 1)
					(thickness 0.15)
				)
				(justify mirror)
			)
		)
		(sheetname "/Ethernet/")
		(sheetfile "ethernet.kicad_sch")
		(attr smd)
		(fp_rect
			(start -0.925 0.47)
			(end 0.925 -0.47)
			(stroke
				(width 0.05)
				(type default)
			)
			(fill no)
			(layer "B.CrtYd")
		)
		(fp_line
			(start -0.494 0.25)
			(end 0.504 0.25)
			(stroke
				(width 0.15)
				(type solid)
			)
			(layer "B.Fab")
		)
		(fp_line
			(start 0.504 0.25)
			(end 0.504 -0.248)
			(stroke
				(width 0.15)
				(type solid)
			)
			(layer "B.Fab")
		)
		(fp_line
			(start -0.494 -0.248)
			(end -0.494 0.25)
			(stroke
				(width 0.15)
				(type solid)
			)
			(layer "B.Fab")
		)
		(fp_line
			(start 0.504 -0.248)
			(end -0.494 -0.248)
			(stroke
				(width 0.15)
				(type solid)
			)
			(layer "B.Fab")
		)
		(pad "1" smd roundrect
			(at -0.48 0 270)
			(size 0.59 0.64)
			(layers "B.Cu" "B.Mask" "B.Paste")
			(roundrect_rratio 0.25)
			(net 1 "GND")
			(pintype "passive")
		)
		(pad "2" smd roundrect
			(at 0.48 0 270)
			(size 0.59 0.64)
			(layers "B.Cu" "B.Mask" "B.Paste")
			(roundrect_rratio 0.25)
			(net 405 "/Ethernet/AVDDL")
			(pintype "passive")
		)
	)
	(footprint "antmicro-footprints:C_0402_1005Metric"
		(layer "B.Cu")
		(at 106.1 90.75 -90)
		(descr "Capacitor SMD 0402")
		(tags "capacitor SMD 0402")
		(property "Reference" "C211"
			(at -3.649 -0.4 90)
			(layer "B.SilkS")
			(effects
				(font
					(size 0.7 0.7)
					(thickness 0.15)
				)
				(justify left bottom mirror)
			)
		)
		(property "Value" "C_10n_0402"
			(at 0 -1.4 90)
			(layer "B.Fab")
			(effects
				(font
					(size 0.7 0.7)
					(thickness 0.15)
				)
				(justify left bottom mirror)
			)
		)
		(property "Datasheet" "https://www.murata.com/products/productdetail?partno=GRM155R71H103KA88%23"
			(at 0 0 270)
			(layer "F.Fab")
			(hide yes)
			(effects
				(font
					(size 1.27 1.27)
					(thickness 0.15)
				)
			)
		)
		(property "Description" "SMD Multilayer Ceramic Capacitor, 10000 pF, 50 V, 0402 [1005 Metric], ± 10%, X7R, GRM Series"
			(at 0 0 270)
			(layer "F.Fab")
			(hide yes)
			(effects
				(font
					(size 1.27 1.27)
					(thickness 0.15)
				)
			)
		)
		(property "Author" "Antmicro"
			(at 15.35 196.85 0)
			(layer "B.Fab")
			(hide yes)
			(effects
				(font
					(size 1 1)
					(thickness 0.15)
				)
				(justify mirror)
			)
		)
		(property "Dielectric" "X7R"
			(at 15.35 196.85 0)
			(layer "B.Fab")
			(hide yes)
			(effects
				(font
					(size 1 1)
					(thickness 0.15)
				)
				(justify mirror)
			)
		)
		(property "License" "Apache-2.0"
			(at 15.35 196.85 0)
			(layer "B.Fab")
			(hide yes)
			(effects
				(font
					(size 1 1)
					(thickness 0.15)
				)
				(justify mirror)
			)
		)
		(property "MPN" "GRM155R71H103KA88D"
			(at 15.35 196.85 0)
			(layer "B.Fab")
			(hide yes)
			(effects
				(font
					(size 1 1)
					(thickness 0.15)
				)
				(justify mirror)
			)
		)
		(property "Manufacturer" "Murata"
			(at 15.35 196.85 0)
			(layer "B.Fab")
			(hide yes)
			(effects
				(font
					(size 1 1)
					(thickness 0.15)
				)
				(justify mirror)
			)
		)
		(property "Val" "10n"
			(at 15.35 196.85 0)
			(layer "B.Fab")
			(hide yes)
			(effects
				(font
					(size 1 1)
					(thickness 0.15)
				)
				(justify mirror)
			)
		)
		(property "Voltage" "50V"
			(at 15.35 196.85 0)
			(layer "B.Fab")
			(hide yes)
			(effects
				(font
					(size 1 1)
					(thickness 0.15)
				)
				(justify mirror)
			)
		)
		(sheetname "/Ethernet/")
		(sheetfile "ethernet.kicad_sch")
		(attr smd)
		(fp_rect
			(start -0.925 0.47)
			(end 0.925 -0.47)
			(stroke
				(width 0.05)
				(type default)
			)
			(fill no)
			(layer "B.CrtYd")
		)
		(fp_line
			(start -0.494 0.25)
			(end 0.504 0.25)
			(stroke
				(width 0.15)
				(type solid)
			)
			(layer "B.Fab")
		)
		(fp_line
			(start 0.504 0.25)
			(end 0.504 -0.248)
			(stroke
				(width 0.15)
				(type solid)
			)
			(layer "B.Fab")
		)
		(fp_line
			(start -0.494 -0.248)
			(end -0.494 0.25)
			(stroke
				(width 0.15)
				(type solid)
			)
			(layer "B.Fab")
		)
		(fp_line
			(start 0.504 -0.248)
			(end -0.494 -0.248)
			(stroke
				(width 0.15)
				(type solid)
			)
			(layer "B.Fab")
		)
		(pad "1" smd roundrect
			(at -0.48 0 270)
			(size 0.59 0.64)
			(layers "B.Cu" "B.Mask" "B.Paste")
			(roundrect_rratio 0.25)
			(net 1 "GND")
			(pintype "passive")
		)
		(pad "2" smd roundrect
			(at 0.48 0 270)
			(size 0.59 0.64)
			(layers "B.Cu" "B.Mask" "B.Paste")
			(roundrect_rratio 0.25)
			(net 406 "/Ethernet/AVDDH")
			(pintype "passive")
		)
	)
)
